(kicad_pcb
	(version 20260206)
	(generator "pcbnew")
	(generator_version "10.0")
	(general
		(thickness 1.6)
		(legacy_teardrops no)
	)
	(paper "A4")
	(title_block
		(title "01162023_DA0F0TEBIF0_F0T_Expander_BD_F_brd_V02_OCP.brd")
		(comment 1 "Grand Teton / footprints 4965-4971 of 9728")
	)
	(layers
		(0 "F.Cu" signal "TOP")
		(4 "In1.Cu" signal "GND")
		(6 "In2.Cu" signal "VCC")
		(8 "In3.Cu" signal "VCC1")
		(10 "In4.Cu" signal "GND1")
		(12 "In5.Cu" signal "IN1")
		(14 "In6.Cu" signal "GND2")
		(16 "In7.Cu" signal "IN2")
		(18 "In8.Cu" signal "GND3")
		(20 "In9.Cu" signal "IN3")
		(22 "In10.Cu" signal "GND4")
		(24 "In11.Cu" signal "IN4")
		(26 "In12.Cu" signal "GND5")
		(28 "In13.Cu" signal "IN5")
		(30 "In14.Cu" signal "GND6")
		(32 "In15.Cu" signal "IN6")
		(34 "In16.Cu" signal "GND7")
		(2 "B.Cu" signal "BOTTOM")
		(9 "F.Adhes" user "F.Adhesive")
		(11 "B.Adhes" user "B.Adhesive")
		(13 "F.Paste" user "Package Geometry/Pastemask Top")
		(15 "B.Paste" user "Package Geometry/Pastemask Bottom")
		(5 "F.SilkS" user "Ref Des/Silkscreen Top")
		(7 "B.SilkS" user "Ref Des/Silkscreen Bottom")
		(1 "F.Mask" user "Board Geometry/Soldermask Top")
		(3 "B.Mask" user "Board Geometry/Soldermask Bottom")
		(17 "Dwgs.User" user "User.Drawings")
		(19 "Cmts.User" user "User.Comments")
		(21 "Eco1.User" user "User.Eco1")
		(23 "Eco2.User" user "User.Eco2")
		(25 "Edge.Cuts" user "Board Geometry/Outline")
		(27 "Margin" user)
		(31 "F.CrtYd" user "Package Geometry/Place Bound Top")
		(29 "B.CrtYd" user "Package Geometry/Place Bound Bottom")
		(35 "F.Fab" user "Ref Des/Assembly Top")
		(33 "B.Fab" user "Ref Des/Assembly Bottom")
	)
	(footprint ""
		(layer "F.Cu")
		(at 95.105728 -240.744248)
		(property "Reference" "R820"
			(at 0 0 0)
			(layer "F.SilkS")
			(hide yes)
			(effects
				(font
					(size 1.27 1.27)
				)
			)
		)
		(property "Value" ""
			(at 0 0 0)
			(layer "F.Fab")
			(effects
				(font
					(size 1.27 1.27)
				)
			)
		)
		(duplicate_pad_numbers_are_jumpers no)
		(fp_line
			(start -0.7874 -0.4064)
			(end 0.7874 -0.4064)
			(stroke
				(width 0.1524)
				(type default)
			)
			(layer "F.SilkS")
		)
		(fp_line
			(start -0.7874 0.4064)
			(end -0.7874 -0.4064)
			(stroke
				(width 0.1524)
				(type default)
			)
			(layer "F.SilkS")
		)
		(fp_line
			(start 0.7874 -0.4064)
			(end 0.7874 0.4064)
			(stroke
				(width 0.1524)
				(type default)
			)
			(layer "F.SilkS")
		)
		(fp_line
			(start 0.7874 0.4064)
			(end -0.7874 0.4064)
			(stroke
				(width 0.1524)
				(type default)
			)
			(layer "F.SilkS")
		)
		(fp_line
			(start -0.67945 -0.305054)
			(end -0.12065 -0.305054)
			(stroke
				(width 0.1)
				(type default)
			)
			(layer "F.Fab")
		)
		(fp_line
			(start -0.67945 0.3048)
			(end -0.67945 -0.305054)
			(stroke
				(width 0.1)
				(type default)
			)
			(layer "F.Fab")
		)
		(fp_line
			(start -0.12065 -0.305054)
			(end -0.12065 -0.2794)
			(stroke
				(width 0.1)
				(type default)
			)
			(layer "F.Fab")
		)
		(fp_line
			(start -0.12065 -0.2794)
			(end 0.12065 -0.2794)
			(stroke
				(width 0.1)
				(type default)
			)
			(layer "F.Fab")
		)
		(fp_line
			(start -0.12065 0.2794)
			(end -0.12065 0.3048)
			(stroke
				(width 0.1)
				(type default)
			)
			(layer "F.Fab")
		)
		(fp_line
			(start -0.12065 0.3048)
			(end -0.67945 0.3048)
			(stroke
				(width 0.1)
				(type default)
			)
			(layer "F.Fab")
		)
		(fp_line
			(start 0.120396 0.2794)
			(end -0.12065 0.2794)
			(stroke
				(width 0.1)
				(type default)
			)
			(layer "F.Fab")
		)
		(fp_line
			(start 0.120396 0.3048)
			(end 0.120396 0.2794)
			(stroke
				(width 0.1)
				(type default)
			)
			(layer "F.Fab")
		)
		(fp_line
			(start 0.12065 -0.3048)
			(end 0.67945 -0.3048)
			(stroke
				(width 0.1)
				(type default)
			)
			(layer "F.Fab")
		)
		(fp_line
			(start 0.12065 -0.2794)
			(end 0.12065 -0.3048)
			(stroke
				(width 0.1)
				(type default)
			)
			(layer "F.Fab")
		)
		(fp_line
			(start 0.67945 -0.3048)
			(end 0.67945 0.3048)
			(stroke
				(width 0.1)
				(type default)
			)
			(layer "F.Fab")
		)
		(fp_line
			(start 0.67945 0.3048)
			(end 0.120396 0.3048)
			(stroke
				(width 0.1)
				(type default)
			)
			(layer "F.Fab")
		)
		(pad "1" smd circle
			(at -0.40005 0)
			(size 0 0)
			(layers "F.Cu" "F.Mask" "F.Paste")
			(net "SMB_BIC_I2C6_MUX_PEX_ADC_R_SDA")
		)
		(pad "2" smd circle
			(at 0.40005 0)
			(size 0 0)
			(layers "F.Cu" "F.Mask" "F.Paste")
			(net "SMB_PEX_P1V8_ADC_SDA")
		)
	)
	(footprint ""
		(layer "F.Cu")
		(at 130.168904 -293.5351 90)
		(property "Reference" "PL10"
			(at -4.287774 10.17016 90)
			(unlocked yes)
			(layer "F.SilkS")
			(effects
				(font
					(size 0.7874 0.5842)
					(thickness 0.1524)
				)
				(justify left)
			)
		)
		(property "Value" ""
			(at 0 0 90)
			(layer "F.Fab")
			(effects
				(font
					(size 1.27 1.27)
				)
			)
		)
		(duplicate_pad_numbers_are_jumpers no)
		(fp_line
			(start 4.800092 -3.199892)
			(end 4.800092 -1.6764)
			(stroke
				(width 0.1524)
				(type default)
			)
			(layer "F.SilkS")
		)
		(fp_line
			(start -4.800092 -3.199892)
			(end 4.800092 -3.199892)
			(stroke
				(width 0.1524)
				(type default)
			)
			(layer "F.SilkS")
		)
		(fp_line
			(start -4.800092 -1.6764)
			(end -4.800092 -3.199892)
			(stroke
				(width 0.1524)
				(type default)
			)
			(layer "F.SilkS")
		)
		(fp_line
			(start 4.800092 1.6764)
			(end 4.800092 3.199892)
			(stroke
				(width 0.1524)
				(type default)
			)
			(layer "F.SilkS")
		)
		(fp_line
			(start 4.800092 3.199892)
			(end -4.800092 3.199892)
			(stroke
				(width 0.1524)
				(type default)
			)
			(layer "F.SilkS")
		)
		(fp_line
			(start -4.800092 3.199892)
			(end -4.800092 1.6764)
			(stroke
				(width 0.1524)
				(type default)
			)
			(layer "F.SilkS")
		)
		(fp_line
			(start 4.800092 -3.199892)
			(end 4.800092 3.199892)
			(stroke
				(width 0.1)
				(type default)
			)
			(layer "F.Fab")
		)
		(fp_line
			(start -4.800092 -3.199892)
			(end 4.800092 -3.199892)
			(stroke
				(width 0.1)
				(type default)
			)
			(layer "F.Fab")
		)
		(fp_line
			(start 4.800092 3.199892)
			(end -4.800092 3.199892)
			(stroke
				(width 0.1)
				(type default)
			)
			(layer "F.Fab")
		)
		(fp_line
			(start -4.800092 3.199892)
			(end -4.800092 -3.199892)
			(stroke
				(width 0.1)
				(type default)
			)
			(layer "F.Fab")
		)
		(pad "1" smd rect
			(at -3.074924 0 180)
			(size 3.0988 3.3528)
			(layers "F.Cu" "F.Mask" "F.Paste")
			(net "SW_P0V8_PEX1_PH2")
		)
		(pad "2" smd rect
			(at 3.074924 0 180)
			(size 3.0988 3.3528)
			(layers "F.Cu" "F.Mask" "F.Paste")
			(net "P0V8_PEX1")
		)
	)
	(footprint ""
		(layer "F.Cu")
		(at 98.072448 -8.177022 90)
		(property "Reference" "C2718"
			(at 0 0 90)
			(layer "F.SilkS")
			(hide yes)
			(effects
				(font
					(size 1.27 1.27)
				)
			)
		)
		(property "Value" ""
			(at 0 0 90)
			(layer "F.Fab")
			(effects
				(font
					(size 1.27 1.27)
				)
			)
		)
		(duplicate_pad_numbers_are_jumpers no)
		(fp_line
			(start 0.7874 -0.4064)
			(end 0.7874 0.4064)
			(stroke
				(width 0.1524)
				(type default)
			)
			(layer "F.SilkS")
		)
		(fp_line
			(start -0.7874 -0.4064)
			(end 0.7874 -0.4064)
			(stroke
				(width 0.1524)
				(type default)
			)
			(layer "F.SilkS")
		)
		(fp_line
			(start 0.7874 0.4064)
			(end -0.7874 0.4064)
			(stroke
				(width 0.1524)
				(type default)
			)
			(layer "F.SilkS")
		)
		(fp_line
			(start -0.7874 0.4064)
			(end -0.7874 -0.4064)
			(stroke
				(width 0.1524)
				(type default)
			)
			(layer "F.SilkS")
		)
		(fp_line
			(start -0.12065 -0.305054)
			(end -0.12065 -0.2794)
			(stroke
				(width 0.1)
				(type default)
			)
			(layer "F.Fab")
		)
		(fp_line
			(start -0.67945 -0.305054)
			(end -0.12065 -0.305054)
			(stroke
				(width 0.1)
				(type default)
			)
			(layer "F.Fab")
		)
		(fp_line
			(start 0.67945 -0.3048)
			(end 0.67945 0.3048)
			(stroke
				(width 0.1)
				(type default)
			)
			(layer "F.Fab")
		)
		(fp_line
			(start 0.12065 -0.3048)
			(end 0.67945 -0.3048)
			(stroke
				(width 0.1)
				(type default)
			)
			(layer "F.Fab")
		)
		(fp_line
			(start 0.12065 -0.2794)
			(end 0.12065 -0.3048)
			(stroke
				(width 0.1)
				(type default)
			)
			(layer "F.Fab")
		)
		(fp_line
			(start -0.12065 -0.2794)
			(end 0.12065 -0.2794)
			(stroke
				(width 0.1)
				(type default)
			)
			(layer "F.Fab")
		)
		(fp_line
			(start 0.120396 0.2794)
			(end -0.12065 0.2794)
			(stroke
				(width 0.1)
				(type default)
			)
			(layer "F.Fab")
		)
		(fp_line
			(start -0.12065 0.2794)
			(end -0.12065 0.3048)
			(stroke
				(width 0.1)
				(type default)
			)
			(layer "F.Fab")
		)
		(fp_line
			(start 0.67945 0.3048)
			(end 0.120396 0.3048)
			(stroke
				(width 0.1)
				(type default)
			)
			(layer "F.Fab")
		)
		(fp_line
			(start 0.120396 0.3048)
			(end 0.120396 0.2794)
			(stroke
				(width 0.1)
				(type default)
			)
			(layer "F.Fab")
		)
		(fp_line
			(start -0.12065 0.3048)
			(end -0.67945 0.3048)
			(stroke
				(width 0.1)
				(type default)
			)
			(layer "F.Fab")
		)
		(fp_line
			(start -0.67945 0.3048)
			(end -0.67945 -0.305054)
			(stroke
				(width 0.1)
				(type default)
			)
			(layer "F.Fab")
		)
		(pad "1" smd circle
			(at -0.40005 0 90)
			(size 0 0)
			(layers "F.Cu" "F.Mask" "F.Paste")
			(net "GND")
		)
		(pad "2" smd circle
			(at 0.40005 0 90)
			(size 0 0)
			(layers "F.Cu" "F.Mask" "F.Paste")
			(net "P3V3_SSD3")
		)
	)
	(footprint ""
		(layer "F.Cu")
		(at 104.699054 -386.917184 180)
		(property "Reference" "R6292"
			(at 0 0 180)
			(layer "F.SilkS")
			(hide yes)
			(effects
				(font
					(size 1.27 1.27)
				)
			)
		)
		(property "Value" ""
			(at 0 0 180)
			(layer "F.Fab")
			(effects
				(font
					(size 1.27 1.27)
				)
			)
		)
		(duplicate_pad_numbers_are_jumpers no)
		(fp_line
			(start 0.7874 0.4064)
			(end -0.462026 0.4064)
			(stroke
				(width 0.1524)
				(type default)
			)
			(layer "F.SilkS")
		)
		(fp_line
			(start 0.7874 -0.4064)
			(end 0.7874 0.4064)
			(stroke
				(width 0.1524)
				(type default)
			)
			(layer "F.SilkS")
		)
		(fp_line
			(start -0.483362 -0.4064)
			(end 0.7874 -0.4064)
			(stroke
				(width 0.1524)
				(type default)
			)
			(layer "F.SilkS")
		)
		(fp_line
			(start 0.67945 0.3048)
			(end 0.120396 0.3048)
			(stroke
				(width 0.1)
				(type default)
			)
			(layer "F.Fab")
		)
		(fp_line
			(start 0.67945 -0.3048)
			(end 0.67945 0.3048)
			(stroke
				(width 0.1)
				(type default)
			)
			(layer "F.Fab")
		)
		(fp_line
			(start 0.12065 -0.2794)
			(end 0.12065 -0.3048)
			(stroke
				(width 0.1)
				(type default)
			)
			(layer "F.Fab")
		)
		(fp_line
			(start 0.12065 -0.3048)
			(end 0.67945 -0.3048)
			(stroke
				(width 0.1)
				(type default)
			)
			(layer "F.Fab")
		)
		(fp_line
			(start 0.120396 0.3048)
			(end 0.120396 0.2794)
			(stroke
				(width 0.1)
				(type default)
			)
			(layer "F.Fab")
		)
		(fp_line
			(start 0.120396 0.2794)
			(end -0.12065 0.2794)
			(stroke
				(width 0.1)
				(type default)
			)
			(layer "F.Fab")
		)
		(fp_line
			(start -0.12065 0.3048)
			(end -0.67945 0.3048)
			(stroke
				(width 0.1)
				(type default)
			)
			(layer "F.Fab")
		)
		(fp_line
			(start -0.12065 0.2794)
			(end -0.12065 0.3048)
			(stroke
				(width 0.1)
				(type default)
			)
			(layer "F.Fab")
		)
		(fp_line
			(start -0.12065 -0.2794)
			(end 0.12065 -0.2794)
			(stroke
				(width 0.1)
				(type default)
			)
			(layer "F.Fab")
		)
		(fp_line
			(start -0.12065 -0.305054)
			(end -0.12065 -0.2794)
			(stroke
				(width 0.1)
				(type default)
			)
			(layer "F.Fab")
		)
		(fp_line
			(start -0.67945 0.3048)
			(end -0.67945 -0.305054)
			(stroke
				(width 0.1)
				(type default)
			)
			(layer "F.Fab")
		)
		(fp_line
			(start -0.67945 -0.305054)
			(end -0.12065 -0.305054)
			(stroke
				(width 0.1)
				(type default)
			)
			(layer "F.Fab")
		)
		(pad "1" smd circle
			(at -0.40005 0 180)
			(size 0 0)
			(layers "F.Cu" "F.Mask" "F.Paste")
			(net "USB2_GPU_HMC_R_DN")
		)
		(pad "2" smd circle
			(at 0.40005 0 180)
			(size 0 0)
			(layers "F.Cu" "F.Mask" "F.Paste")
			(net "GND")
		)
	)
	(footprint ""
		(layer "F.Cu")
		(at 324.192646 -118.446804)
		(property "Reference" "PC903"
			(at 0 0 0)
			(layer "F.SilkS")
			(hide yes)
			(effects
				(font
					(size 1.27 1.27)
				)
			)
		)
		(property "Value" ""
			(at 0 0 0)
			(layer "F.Fab")
			(effects
				(font
					(size 1.27 1.27)
				)
			)
		)
		(duplicate_pad_numbers_are_jumpers no)
		(fp_line
			(start -1.524 -0.762)
			(end 1.524 -0.762)
			(stroke
				(width 0.1524)
				(type default)
			)
			(layer "F.SilkS")
		)
		(fp_line
			(start -1.524 0.762)
			(end -1.524 -0.762)
			(stroke
				(width 0.1524)
				(type default)
			)
			(layer "F.SilkS")
		)
		(fp_line
			(start 1.524 -0.762)
			(end 1.524 0.762)
			(stroke
				(width 0.1524)
				(type default)
			)
			(layer "F.SilkS")
		)
		(fp_line
			(start 1.524 0.762)
			(end -1.524 0.762)
			(stroke
				(width 0.1524)
				(type default)
			)
			(layer "F.SilkS")
		)
		(fp_line
			(start -1.1049 -0.724916)
			(end -1.1049 0.724916)
			(stroke
				(width 0.1)
				(type default)
			)
			(layer "F.Fab")
		)
		(fp_line
			(start -1.1049 0.724916)
			(end 1.1049 0.724916)
			(stroke
				(width 0.1)
				(type default)
			)
			(layer "F.Fab")
		)
		(fp_line
			(start 1.1049 -0.724916)
			(end -1.1049 -0.724916)
			(stroke
				(width 0.1)
				(type default)
			)
			(layer "F.Fab")
		)
		(fp_line
			(start 1.1049 0.724916)
			(end 1.1049 -0.724916)
			(stroke
				(width 0.1)
				(type default)
			)
			(layer "F.Fab")
		)
		(pad "1" smd rect
			(at -0.889 0 180)
			(size 1.016 1.27)
			(layers "F.Cu" "F.Mask" "F.Paste")
			(net "P3V3_NIC5")
		)
		(pad "2" smd rect
			(at 0.889 0 180)
			(size 1.016 1.27)
			(layers "F.Cu" "F.Mask" "F.Paste")
			(net "GND")
		)
	)
	(footprint ""
		(layer "F.Cu")
		(at 258.44373 -47.92091)
		(property "Reference" "R592"
			(at 0 0 0)
			(layer "F.SilkS")
			(hide yes)
			(effects
				(font
					(size 1.27 1.27)
				)
			)
		)
		(property "Value" ""
			(at 0 0 0)
			(layer "F.Fab")
			(effects
				(font
					(size 1.27 1.27)
				)
			)
		)
		(duplicate_pad_numbers_are_jumpers no)
		(fp_line
			(start -0.7874 -0.4064)
			(end 0.7874 -0.4064)
			(stroke
				(width 0.1524)
				(type default)
			)
			(layer "F.SilkS")
		)
		(fp_line
			(start -0.7874 0.4064)
			(end -0.7874 -0.4064)
			(stroke
				(width 0.1524)
				(type default)
			)
			(layer "F.SilkS")
		)
		(fp_line
			(start 0.7874 -0.4064)
			(end 0.7874 0.4064)
			(stroke
				(width 0.1524)
				(type default)
			)
			(layer "F.SilkS")
		)
		(fp_line
			(start 0.7874 0.4064)
			(end -0.7874 0.4064)
			(stroke
				(width 0.1524)
				(type default)
			)
			(layer "F.SilkS")
		)
		(fp_line
			(start -0.67945 -0.305054)
			(end -0.12065 -0.305054)
			(stroke
				(width 0.1)
				(type default)
			)
			(layer "F.Fab")
		)
		(fp_line
			(start -0.67945 0.3048)
			(end -0.67945 -0.305054)
			(stroke
				(width 0.1)
				(type default)
			)
			(layer "F.Fab")
		)
		(fp_line
			(start -0.12065 -0.305054)
			(end -0.12065 -0.2794)
			(stroke
				(width 0.1)
				(type default)
			)
			(layer "F.Fab")
		)
		(fp_line
			(start -0.12065 -0.2794)
			(end 0.12065 -0.2794)
			(stroke
				(width 0.1)
				(type default)
			)
			(layer "F.Fab")
		)
		(fp_line
			(start -0.12065 0.2794)
			(end -0.12065 0.3048)
			(stroke
				(width 0.1)
				(type default)
			)
			(layer "F.Fab")
		)
		(fp_line
			(start -0.12065 0.3048)
			(end -0.67945 0.3048)
			(stroke
				(width 0.1)
				(type default)
			)
			(layer "F.Fab")
		)
		(fp_line
			(start 0.120396 0.2794)
			(end -0.12065 0.2794)
			(stroke
				(width 0.1)
				(type default)
			)
			(layer "F.Fab")
		)
		(fp_line
			(start 0.120396 0.3048)
			(end 0.120396 0.2794)
			(stroke
				(width 0.1)
				(type default)
			)
			(layer "F.Fab")
		)
		(fp_line
			(start 0.12065 -0.3048)
			(end 0.67945 -0.3048)
			(stroke
				(width 0.1)
				(type default)
			)
			(layer "F.Fab")
		)
		(fp_line
			(start 0.12065 -0.2794)
			(end 0.12065 -0.3048)
			(stroke
				(width 0.1)
				(type default)
			)
			(layer "F.Fab")
		)
		(fp_line
			(start 0.67945 -0.3048)
			(end 0.67945 0.3048)
			(stroke
				(width 0.1)
				(type default)
			)
			(layer "F.Fab")
		)
		(fp_line
			(start 0.67945 0.3048)
			(end 0.120396 0.3048)
			(stroke
				(width 0.1)
				(type default)
			)
			(layer "F.Fab")
		)
		(pad "1" smd circle
			(at -0.40005 0)
			(size 0 0)
			(layers "F.Cu" "F.Mask" "F.Paste")
			(net "P3V3_AUX")
		)
		(pad "2" smd circle
			(at 0.40005 0)
			(size 0 0)
			(layers "F.Cu" "F.Mask" "F.Paste")
			(net "SSD_8_15_ADC_ALERT_N")
		)
	)
	(footprint ""
		(layer "F.Cu")
		(at 350.380554 -84.930234)
		(property "Reference" "R1595"
			(at 0 0 0)
			(layer "F.SilkS")
			(hide yes)
			(effects
				(font
					(size 1.27 1.27)
				)
			)
		)
		(property "Value" ""
			(at 0 0 0)
			(layer "F.Fab")
			(effects
				(font
					(size 1.27 1.27)
				)
			)
		)
		(duplicate_pad_numbers_are_jumpers no)
		(fp_line
			(start -0.7874 -0.4064)
			(end 0.7874 -0.4064)
			(stroke
				(width 0.1524)
				(type default)
			)
			(layer "F.SilkS")
		)
		(fp_line
			(start -0.7874 0.4064)
			(end -0.7874 -0.4064)
			(stroke
				(width 0.1524)
				(type default)
			)
			(layer "F.SilkS")
		)
		(fp_line
			(start 0.7874 -0.4064)
			(end 0.7874 0.4064)
			(stroke
				(width 0.1524)
				(type default)
			)
			(layer "F.SilkS")
		)
		(fp_line
			(start 0.7874 0.4064)
			(end -0.7874 0.4064)
			(stroke
				(width 0.1524)
				(type default)
			)
			(layer "F.SilkS")
		)
		(fp_line
			(start -0.67945 -0.305054)
			(end -0.12065 -0.305054)
			(stroke
				(width 0.1)
				(type default)
			)
			(layer "F.Fab")
		)
		(fp_line
			(start -0.67945 0.3048)
			(end -0.67945 -0.305054)
			(stroke
				(width 0.1)
				(type default)
			)
			(layer "F.Fab")
		)
		(fp_line
			(start -0.12065 -0.305054)
			(end -0.12065 -0.2794)
			(stroke
				(width 0.1)
				(type default)
			)
			(layer "F.Fab")
		)
		(fp_line
			(start -0.12065 -0.2794)
			(end 0.12065 -0.2794)
			(stroke
				(width 0.1)
				(type default)
			)
			(layer "F.Fab")
		)
		(fp_line
			(start -0.12065 0.2794)
			(end -0.12065 0.3048)
			(stroke
				(width 0.1)
				(type default)
			)
			(layer "F.Fab")
		)
		(fp_line
			(start -0.12065 0.3048)
			(end -0.67945 0.3048)
			(stroke
				(width 0.1)
				(type default)
			)
			(layer "F.Fab")
		)
		(fp_line
			(start 0.120396 0.2794)
			(end -0.12065 0.2794)
			(stroke
				(width 0.1)
				(type default)
			)
			(layer "F.Fab")
		)
		(fp_line
			(start 0.120396 0.3048)
			(end 0.120396 0.2794)
			(stroke
				(width 0.1)
				(type default)
			)
			(layer "F.Fab")
		)
		(fp_line
			(start 0.12065 -0.3048)
			(end 0.67945 -0.3048)
			(stroke
				(width 0.1)
				(type default)
			)
			(layer "F.Fab")
		)
		(fp_line
			(start 0.12065 -0.2794)
			(end 0.12065 -0.3048)
			(stroke
				(width 0.1)
				(type default)
			)
			(layer "F.Fab")
		)
		(fp_line
			(start 0.67945 -0.3048)
			(end 0.67945 0.3048)
			(stroke
				(width 0.1)
				(type default)
			)
			(layer "F.Fab")
		)
		(fp_line
			(start 0.67945 0.3048)
			(end 0.120396 0.3048)
			(stroke
				(width 0.1)
				(type default)
			)
			(layer "F.Fab")
		)
		(pad "1" smd circle
			(at -0.40005 0)
			(size 0 0)
			(layers "F.Cu" "F.Mask" "F.Paste")
			(net "P3V3_AUX")
		)
		(pad "2" smd circle
			(at 0.40005 0)
			(size 0 0)
			(layers "F.Cu" "F.Mask" "F.Paste")
			(net "SMB_BIC_I2C9_MUX1_SSD10_R_SDA")
		)
	)
)
